FILE_TYPE = MULTI_PHYS_TABLE;

PART '74LVC1G126SE7'

{========================================================================================}
:VALUE            | PART_TYPE | MATERIAL | PART_NUMBER    = STANDARD    | LIFECYCLE      | PART_NUMBER   | JEDEC_TYPE           | DESCRIPTION                            | MANUFTR | MANUF_PN         | RD_CMPLS_LVL | CMPLS_LVL | FROM_PJ    | CLASS | DIP_SMD | DATA                     | EE_CHECK_LIST | FP_ECN | PSL | CREATOR | STATUS | MSD | ESD_CDM | ESD_HBM | ESD_MM | PIN_LENGTH_SHORT_PIN | PIN_LENGTH_LONG_PIN | CREATEDAY  ;
{========================================================================================}
 '74LVC1G126SE-7' | 'SMLF'    | 'IC'     | 'AL1G0126009'(!) = ''               | ''               | 'AL1G0126009' |'SOT353_0-65_2X1-25'| 'IC OTHER(5P) 74LVC1G126SE-7 (SOT353)' | 'DDS'   | '74LVC1G126SE-7' | 'EP(V1)'     | 'EP(V1)'  | 'F0C-IVES' | 'IC'  | ''      | 'DDS_74LVC1G126SE-7.pdf' | ''            | ''     | ''  | ''      | ''     | ''  | ''      | ''      | ''     | '0 MILS'             | '0 MILS'            | '20210615'
 '74LVC1G126SE-7' | 'SMLF'    | 'EMPTY'  | 'AL1G0126009'(!) = ''               | ''               | 'AL1G0126009' |'SOT353_0-65_2X1-25'| 'IC OTHER(5P) 74LVC1G126SE-7 (SOT353)' | 'DDS'   | '74LVC1G126SE-7' | 'EP(V1)'     | 'EP(V1)'  | 'F0C-IVES' | 'IC'  | ''      | 'DDS_74LVC1G126SE-7.pdf' | ''            | ''     | ''  | ''      | ''     | ''  | ''      | ''      | ''     | '0 MILS'             | '0 MILS'            | '20210615'

END_PART

END.

